# BASEBOARD_FAB2 (Tioga Pass) — schematic netlist excerpt (pin names and nets, part order shuffled) for the footprints in the layout excerpt that follows; sources: Cadence DE-HDL packaged netlist, KiCad conversion of Wiwynn_Tioga_Pass_MB.brd

EU1G2  PXM1310B  IC  pkg QFN  page 223
  BPWM1  = NC
  DNC(0)  = NC
  APWM3  = NC
  APWM2  = VR_PVDDQ_GHJ_PWM2
  APWM1  = VR_PVDDQ_GHJ_PWM1
  SDA  = SMB_VR_STBY_LVC3_SDA
  SCL  = SMB_VR_STBY_LVC3_SCL
  RESET_N  = NC
  AVRRDY  = PWRGD_PVDDQ_GHJ_R
  AVREN  = VR_PVDDQ_GHJ_VREN
  VRHOT_N  = IRQ_PVDDQ_GHJ_VRHOT_LVT3_R_N
  PINALRT_N  = NC
  MP0  = PU_VR_PVDDQ_GHJ_FAULT1
  MP1  = TP_PVDDQ_GHJ_MP1
  VCLK  = SVID_CLK_PVDDQ_GHJ
  VDIO  = SVID_VDIO_PVDDQ_GHJ
  VALRT_N  = SVID_ALERT_PVDDQ_GHJ
  MP2  = TP_PVDDQ_GHJ_MP2
  AVSEN  = VR_PVDDQ_GHJ_AVSP
  AVREF  = VSENSE_PVDDQ_GHJ_N
  AIREF1  = VR_PVDDQ_GHJ_AIREF1
  AISEN1  = ISENSE_PVDDQ_GHJ_PH1_IMON
  AIREF2  = VR_PVDDQ_GHJ_AIREF2
  AISEN2  = ISENSE_PVDDQ_GHJ_PH2_IMON
  AIREF3  = NC
  AISEN3  = NC
  GND  = GND
  DNC(1)  = NC
  BVSEN  = NC
  BVREF  = NC
  BIREF1  = NC
  BISEN1  = GND
  XADDR2  = VR_PVDDQ_GHJ_XADDR2
  BTSEN  = NC
  ATSEN  = A_TSENSE_PVDDQ_GHJ
  XADDR1  = VR_PVDDQ_GHJ_XADDR1
  VINSEN  = VR_PVDDQ_GHJ_VINSEN
  IINSEN  = VR_PVDDQ_GHJ_AIINSEN
  VDD  = VR_PVDDQ_GHJ_VDD
  VD12  = VR_PVDDQ_GHJ_VD12
  THPAD  = GND

(kicad_pcb
	(version 20260206)
	(generator "pcbnew")
	(generator_version "10.0")
	(general
		(thickness 1.6)
		(legacy_teardrops no)
	)
	(paper "A4")
	(title_block
		(title "Wiwynn_Tioga_Pass_MB.brd")
		(comment 1 "Tioga Pass / footprint 2178 of 4770 (EU1G2), pads 35-41 of 41")
	)
	(layers
		(0 "F.Cu" signal "TOP")
		(4 "In1.Cu" signal "L2GND")
		(6 "In2.Cu" signal "L3")
		(8 "In3.Cu" signal "L4GND")
		(10 "In4.Cu" signal "L5")
		(12 "In5.Cu" signal "L6GND")
		(14 "In6.Cu" signal "L7VCC")
		(16 "In7.Cu" signal "L8VCC")
		(18 "In8.Cu" signal "L9GND")
		(20 "In9.Cu" signal "L10")
		(22 "In10.Cu" signal "L11GND")
		(24 "In11.Cu" signal "L12")
		(26 "In12.Cu" signal "L13GND")
		(2 "B.Cu" signal "BOTTOM")
		(9 "F.Adhes" user "F.Adhesive")
		(11 "B.Adhes" user "B.Adhesive")
		(13 "F.Paste" user "Package Geometry/Pastemask Top")
		(15 "B.Paste" user "Package Geometry/Pastemask Bottom")
		(5 "F.SilkS" user "Ref Des/Silkscreen Top")
		(7 "B.SilkS" user "Ref Des/Silkscreen Bottom")
		(1 "F.Mask" user "Board Geometry/Soldermask Top")
		(3 "B.Mask" user "Board Geometry/Soldermask Bottom")
		(17 "Dwgs.User" user "User.Drawings")
		(19 "Cmts.User" user "User.Comments")
		(21 "Eco1.User" user "User.Eco1")
		(23 "Eco2.User" user "User.Eco2")
		(25 "Edge.Cuts" user "Board Geometry/Outline")
		(27 "Margin" user)
		(31 "F.CrtYd" user "Package Geometry/Place Bound Top")
		(29 "B.CrtYd" user "Package Geometry/Place Bound Bottom")
		(35 "F.Fab" user "Ref Des/Assembly Top")
		(33 "B.Fab" user "Ref Des/Assembly Bottom")
	)
	(footprint ""
		(layer "F.Cu")
		(at 10.033 0.24765 180)
		(property "Reference" "EU1G2"
			(at 2.4638 -3.53187 0)
			(unlocked yes)
			(layer "F.SilkS")
			(effects
				(font
					(size 0.7874 0.5842)
					(thickness 0.1524)
				)
				(justify left)
			)
		)
		(property "Value" ""
			(at 0 0 180)
			(layer "F.Fab")
			(effects
				(font
					(size 1.27 1.27)
				)
			)
		)
		(duplicate_pad_numbers_are_jumpers no)
		(pad "35" smd custom
			(at 0.199898 -2.4511 180)
			(size 0.0508 0.0508)
			(layers "F.Cu" "F.Mask" "F.Paste")
			(net "A_TSENSE_PVDDQ_GHJ")
			(options
				(clearance outline)
				(anchor circle)
			)
			(primitives
				(gr_poly
					(pts
						(arc
							(start 0.1016 0.254)
							(mid 0 0.3556)
							(end -0.1016 0.254)
						)
						(xy -0.1016 -0.3556) (xy 0.1016 -0.3556)
					)
					(width 0)
					(fill yes)
				)
			)
		)
		(pad "36" smd custom
			(at -0.199898 -2.4511 180)
			(size 0.0508 0.0508)
			(layers "F.Cu" "F.Mask" "F.Paste")
			(net "VR_PVDDQ_GHJ_XADDR1")
			(options
				(clearance outline)
				(anchor circle)
			)
			(primitives
				(gr_poly
					(pts
						(arc
							(start 0.1016 0.254)
							(mid 0 0.3556)
							(end -0.1016 0.254)
						)
						(xy -0.1016 -0.3556) (xy 0.1016 -0.3556)
					)
					(width 0)
					(fill yes)
				)
			)
		)
		(pad "37" smd custom
			(at -0.599948 -2.4511 180)
			(size 0.0508 0.0508)
			(layers "F.Cu" "F.Mask" "F.Paste")
			(net "VR_PVDDQ_GHJ_VINSEN")
			(options
				(clearance outline)
				(anchor circle)
			)
			(primitives
				(gr_poly
					(pts
						(arc
							(start 0.1016 0.254)
							(mid 0 0.3556)
							(end -0.1016 0.254)
						)
						(xy -0.1016 -0.3556) (xy 0.1016 -0.3556)
					)
					(width 0)
					(fill yes)
				)
			)
		)
		(pad "38" smd custom
			(at -0.999998 -2.4511 180)
			(size 0.0508 0.0508)
			(layers "F.Cu" "F.Mask" "F.Paste")
			(net "VR_PVDDQ_GHJ_AIINSEN")
			(options
				(clearance outline)
				(anchor circle)
			)
			(primitives
				(gr_poly
					(pts
						(arc
							(start 0.1016 0.254)
							(mid 0 0.3556)
							(end -0.1016 0.254)
						)
						(xy -0.1016 -0.3556) (xy 0.1016 -0.3556)
					)
					(width 0)
					(fill yes)
				)
			)
		)
		(pad "39" smd custom
			(at -1.400048 -2.4511 180)
			(size 0.0508 0.0508)
			(layers "F.Cu" "F.Mask" "F.Paste")
			(net "VR_PVDDQ_GHJ_VDD")
			(options
				(clearance outline)
				(anchor circle)
			)
			(primitives
				(gr_poly
					(pts
						(arc
							(start 0.1016 0.254)
							(mid 0 0.3556)
							(end -0.1016 0.254)
						)
						(xy -0.1016 -0.3556) (xy 0.1016 -0.3556)
					)
					(width 0)
					(fill yes)
				)
			)
		)
		(pad "40" smd custom
			(at -1.800098 -2.4511 180)
			(size 0.0508 0.0508)
			(layers "F.Cu" "F.Mask" "F.Paste")
			(net "VR_PVDDQ_GHJ_VD12")
			(options
				(clearance outline)
				(anchor circle)
			)
			(primitives
				(gr_poly
					(pts
						(arc
							(start 0.1016 0.254)
							(mid 0 0.3556)
							(end -0.1016 0.254)
						)
						(xy -0.1016 -0.3556) (xy 0.1016 -0.3556)
					)
					(width 0)
					(fill yes)
				)
			)
		)
		(pad "41" smd rect
			(at 0 0 180)
			(size 3.683 3.683)
			(layers "F.Cu" "F.Mask" "F.Paste")
			(net "GND")
		)
	)
)
